(kicad_pcb
	(version 20241229)
	(generator "pcbnew")
	(generator_version "9.0")
	(general
		(thickness 1.294)
		(legacy_teardrops no)
	)
	(paper "A3")
	(title_block
		(title "Kintex 410T devboard")
		(date "2024-04-03")
		(rev "1.1.2")
		(comment 9 "footprints 378-381 of 975")
	)
	(layers
		(0 "F.Cu" mixed)
		(4 "In1.Cu" power)
		(6 "In2.Cu" power)
		(8 "In3.Cu" mixed)
		(10 "In4.Cu" power)
		(12 "In5.Cu" mixed)
		(14 "In6.Cu" power)
		(16 "In7.Cu" mixed)
		(18 "In8.Cu" power)
		(2 "B.Cu" mixed)
		(9 "F.Adhes" user "F.Adhesive")
		(11 "B.Adhes" user "B.Adhesive")
		(13 "F.Paste" user)
		(15 "B.Paste" user)
		(5 "F.SilkS" user "F.Silkscreen")
		(7 "B.SilkS" user "B.Silkscreen")
		(1 "F.Mask" user)
		(3 "B.Mask" user)
		(17 "Dwgs.User" user "User.Drawings")
		(19 "Cmts.User" user "User.Comments")
		(21 "Eco1.User" user "User.Eco1")
		(23 "Eco2.User" user "User.Eco2")
		(25 "Edge.Cuts" user)
		(27 "Margin" user)
		(31 "F.CrtYd" user "F.Courtyard")
		(29 "B.CrtYd" user "B.Courtyard")
		(35 "F.Fab" user)
		(33 "B.Fab" user)
	)
	(footprint "antmicro-footprints:SOT-23-6"
		(layer "F.Cu")
		(at 191 168.749 90)
		(property "Reference" "U10"
			(at 1.699 -2.05 180)
			(layer "F.SilkS")
			(effects
				(font
					(size 0.7 0.7)
					(thickness 0.15)
				)
				(justify left bottom)
			)
		)
		(property "Value" "LTC4412IS6"
			(at -1.75 2.75 90)
			(layer "F.Fab")
			(effects
				(font
					(size 0.7 0.7)
					(thickness 0.15)
				)
				(justify left bottom)
			)
		)
		(property "Description" "Ideal diode controller"
			(at 0 0 90)
			(layer "F.Fab")
			(hide yes)
			(effects
				(font
					(size 1.27 1.27)
					(thickness 0.15)
				)
			)
		)
		(property "Author" "Antmicro"
			(at 359.749 -22.251 0)
			(layer "F.Fab")
			(hide yes)
			(effects
				(font
					(size 1 1)
					(thickness 0.15)
				)
			)
		)
		(property "License" "Apache-2.0"
			(at 359.749 -22.251 0)
			(layer "F.Fab")
			(hide yes)
			(effects
				(font
					(size 1 1)
					(thickness 0.15)
				)
			)
		)
		(property "MPN" "LTC4412IS6#TRMPBF"
			(at 359.749 -22.251 0)
			(layer "F.Fab")
			(hide yes)
			(effects
				(font
					(size 1 1)
					(thickness 0.15)
				)
			)
		)
		(property "Manufacturer" "Analog Devices"
			(at 359.749 -22.251 0)
			(layer "F.Fab")
			(hide yes)
			(effects
				(font
					(size 1 1)
					(thickness 0.15)
				)
			)
		)
		(sheetname "Power supply")
		(sheetfile "power-supply.kicad_sch")
		(attr smd)
		(fp_line
			(start 1.45 -0.7)
			(end 1.45 -0.4)
			(stroke
				(width 0.12)
				(type solid)
			)
			(layer "F.SilkS")
		)
		(fp_line
			(start 1.3 -0.7)
			(end 1.45 -0.7)
			(stroke
				(width 0.12)
				(type solid)
			)
			(layer "F.SilkS")
		)
		(fp_line
			(start -1.3 -0.7)
			(end -1.45 -0.7)
			(stroke
				(width 0.12)
				(type solid)
			)
			(layer "F.SilkS")
		)
		(fp_line
			(start -1.45 -0.7)
			(end -1.45 -0.4)
			(stroke
				(width 0.12)
				(type solid)
			)
			(layer "F.SilkS")
		)
		(fp_line
			(start 1.45 0.7)
			(end 1.45 0.4)
			(stroke
				(width 0.12)
				(type solid)
			)
			(layer "F.SilkS")
		)
		(fp_line
			(start 1.3 0.7)
			(end 1.45 0.7)
			(stroke
				(width 0.12)
				(type solid)
			)
			(layer "F.SilkS")
		)
		(fp_line
			(start -1.45 0.7)
			(end -1.45 0.4)
			(stroke
				(width 0.12)
				(type solid)
			)
			(layer "F.SilkS")
		)
		(fp_rect
			(start -1.55 -1.85)
			(end 1.55 1.75)
			(stroke
				(width 0.05)
				(type solid)
			)
			(fill no)
			(layer "F.CrtYd")
		)
		(fp_line
			(start 1.5 -0.7)
			(end 1.5 0.7)
			(stroke
				(width 0.1)
				(type solid)
			)
			(layer "F.Fab")
		)
		(fp_line
			(start -1.5 -0.7)
			(end 1.5 -0.7)
			(stroke
				(width 0.1)
				(type solid)
			)
			(layer "F.Fab")
		)
		(fp_line
			(start 1.5 0.7)
			(end -1.5 0.7)
			(stroke
				(width 0.1)
				(type solid)
			)
			(layer "F.Fab")
		)
		(fp_line
			(start -1.5 0.7)
			(end -1.5 -0.7)
			(stroke
				(width 0.1)
				(type solid)
			)
			(layer "F.Fab")
		)
		(fp_text user "."
			(at -1.4 1.2 270)
			(layer "F.SilkS")
			(effects
				(font
					(size 1 1)
					(thickness 0.15)
				)
			)
		)
		(pad "1" smd roundrect
			(at -0.954 1.1 90)
			(size 0.55 1)
			(layers "F.Cu" "F.Mask" "F.Paste")
			(roundrect_rratio 0.15)
			(net 700 "/Power supply/USB_PD_VBUS")
			(pinfunction "IN")
			(pintype "power_in")
		)
		(pad "2" smd roundrect
			(at -0.003 1.1 90)
			(size 0.55 1)
			(layers "F.Cu" "F.Mask" "F.Paste")
			(roundrect_rratio 0.15)
			(net 1 "GND")
			(pinfunction "GND")
			(pintype "power_in")
		)
		(pad "3" smd roundrect
			(at 0.947 1.1 90)
			(size 0.55 1)
			(layers "F.Cu" "F.Mask" "F.Paste")
			(roundrect_rratio 0.15)
			(net 1 "GND")
			(pinfunction "CTL")
			(pintype "input")
		)
		(pad "4" smd roundrect
			(at 0.947 -1.214 90)
			(size 0.55 1)
			(layers "F.Cu" "F.Mask" "F.Paste")
			(roundrect_rratio 0.15)
			(net 1157 "unconnected-(U10-STAT-Pad4)")
			(pinfunction "STAT")
			(pintype "output+no_connect")
		)
		(pad "5" smd roundrect
			(at -0.003 -1.214 90)
			(size 0.55 1)
			(layers "F.Cu" "F.Mask" "F.Paste")
			(roundrect_rratio 0.15)
			(net 341 "Net-(Q6-G)")
			(pinfunction "GATE")
			(pintype "output")
		)
		(pad "6" smd roundrect
			(at -0.954 -1.214 90)
			(size 0.55 1)
			(layers "F.Cu" "F.Mask" "F.Paste")
			(roundrect_rratio 0.15)
			(net 702 "VDC")
			(pinfunction "SENSE")
			(pintype "input")
		)
	)
	(footprint "antmicro-footprints:PinHeader_2x17_P1.27mm_SMD_Shrouded"
		(layer "F.Cu")
		(at 231.001 88.2225)
		(property "Reference" "J11"
			(at 12.199 -2.9725 0)
			(layer "F.SilkS")
			(effects
				(font
					(size 0.7 0.7)
					(thickness 0.15)
				)
				(justify left bottom)
			)
		)
		(property "Value" "PinHeader_2x17_P1.27mm_SMD_Shrouded"
			(at -3.63 0.37 0)
			(layer "F.Fab")
			(effects
				(font
					(size 0.7 0.7)
					(thickness 0.15)
				)
				(justify left bottom)
			)
		)
		(property "Description" "Pin Header, Wire-to-Board, 1.27 mm, 2 Rows, 34 Contacts, Surface Mount Straight, WR-BHD Series"
			(at 0 0 0)
			(layer "F.Fab")
			(hide yes)
			(effects
				(font
					(size 1.27 1.27)
					(thickness 0.15)
				)
			)
		)
		(property "Author" "Antmicro"
			(at 0 0 0)
			(layer "F.Fab")
			(hide yes)
			(effects
				(font
					(size 1 1)
					(thickness 0.15)
				)
			)
		)
		(property "License" "Apache-2.0"
			(at 0 0 0)
			(layer "F.Fab")
			(hide yes)
			(effects
				(font
					(size 1 1)
					(thickness 0.15)
				)
			)
		)
		(property "MPN" "62703420621"
			(at 0 0 0)
			(layer "F.Fab")
			(hide yes)
			(effects
				(font
					(size 1 1)
					(thickness 0.15)
				)
			)
		)
		(property "Manufacturer" "Würth Elektronik"
			(at 0 0 0)
			(layer "F.Fab")
			(hide yes)
			(effects
				(font
					(size 1 1)
					(thickness 0.15)
				)
			)
		)
		(sheetname "User GPIO + LED + button + DIP switch")
		(sheetfile "user-gpio.kicad_sch")
		(attr smd)
		(fp_line
			(start -14 -2.6)
			(end -14 2.6)
			(stroke
				(width 0.15)
				(type solid)
			)
			(layer "F.SilkS")
		)
		(fp_line
			(start -14 -2.6)
			(end -10.8 -2.6)
			(stroke
				(width 0.15)
				(type solid)
			)
			(layer "F.SilkS")
		)
		(fp_line
			(start -14 2.6)
			(end -10.8 2.6)
			(stroke
				(width 0.15)
				(type solid)
			)
			(layer "F.SilkS")
		)
		(fp_line
			(start 10.8 -2.6)
			(end 14 -2.6)
			(stroke
				(width 0.15)
				(type solid)
			)
			(layer "F.SilkS")
		)
		(fp_line
			(start 10.8 2.6)
			(end 14 2.6)
			(stroke
				(width 0.15)
				(type solid)
			)
			(layer "F.SilkS")
		)
		(fp_line
			(start 14 -2.6)
			(end 14 2.6)
			(stroke
				(width 0.15)
				(type solid)
			)
			(layer "F.SilkS")
		)
		(fp_circle
			(center -10.86 3.07)
			(end -10.809 3.07)
			(stroke
				(width 0.15)
				(type solid)
			)
			(fill yes)
			(layer "F.SilkS")
		)
		(fp_rect
			(start -14.3 -3.5)
			(end 14.3 3.5)
			(stroke
				(width 0.05)
				(type solid)
			)
			(fill no)
			(layer "F.CrtYd")
		)
		(fp_line
			(start -13.96 2.57)
			(end -13.76 2.77)
			(stroke
				(width 0.15)
				(type solid)
			)
			(layer "F.Fab")
		)
		(fp_rect
			(start -13.971 -2.778)
			(end 13.97 2.777)
			(stroke
				(width 0.15)
				(type solid)
			)
			(fill no)
			(layer "F.Fab")
		)
		(pad "1" smd rect
			(at -10.16 1.999)
			(size 0.74 2.8)
			(layers "F.Cu" "F.Mask" "F.Paste")
			(net 1266 "/USER_IO.B1")
			(pintype "passive")
		)
		(pad "2" smd rect
			(at -10.16 -2)
			(size 0.74 2.8)
			(layers "F.Cu" "F.Mask" "F.Paste")
			(net 1 "GND")
			(pintype "passive")
		)
		(pad "3" smd rect
			(at -8.891 1.999)
			(size 0.74 2.8)
			(layers "F.Cu" "F.Mask" "F.Paste")
			(net 1267 "/USER_IO.B3")
			(pintype "passive")
		)
		(pad "4" smd rect
			(at -8.891 -2)
			(size 0.74 2.8)
			(layers "F.Cu" "F.Mask" "F.Paste")
			(net 1 "GND")
			(pintype "passive")
		)
		(pad "5" smd rect
			(at -7.62 1.999)
			(size 0.74 2.8)
			(layers "F.Cu" "F.Mask" "F.Paste")
			(net 1268 "/USER_IO.B5")
			(pintype "passive")
		)
		(pad "6" smd rect
			(at -7.62 -2)
			(size 0.74 2.8)
			(layers "F.Cu" "F.Mask" "F.Paste")
			(net 1269 "/USER_IO.B6")
			(pintype "passive")
		)
		(pad "7" smd rect
			(at -6.351 1.999)
			(size 0.74 2.8)
			(layers "F.Cu" "F.Mask" "F.Paste")
			(net 1270 "/USER_IO.B7")
			(pintype "passive")
		)
		(pad "8" smd rect
			(at -6.351 -2)
			(size 0.74 2.8)
			(layers "F.Cu" "F.Mask" "F.Paste")
			(net 1271 "/USER_IO.B8")
			(pintype "passive")
		)
		(pad "9" smd rect
			(at -5.08 1.999)
			(size 0.74 2.8)
			(layers "F.Cu" "F.Mask" "F.Paste")
			(net 1272 "/USER_IO.B9")
			(pintype "passive")
		)
		(pad "10" smd rect
			(at -5.08 -2)
			(size 0.74 2.8)
			(layers "F.Cu" "F.Mask" "F.Paste")
			(net 1273 "/USER_IO.B10")
			(pintype "passive")
		)
		(pad "11" smd rect
			(at -3.81 1.999)
			(size 0.74 2.8)
			(layers "F.Cu" "F.Mask" "F.Paste")
			(net 1274 "/USER_IO.B11")
			(pintype "passive")
		)
		(pad "12" smd rect
			(at -3.81 -2)
			(size 0.74 2.8)
			(layers "F.Cu" "F.Mask" "F.Paste")
			(net 1275 "/USER_IO.B12")
			(pintype "passive")
		)
		(pad "13" smd rect
			(at -2.54 1.999)
			(size 0.74 2.8)
			(layers "F.Cu" "F.Mask" "F.Paste")
			(net 3 "VCC_USR_B")
			(pintype "passive")
		)
		(pad "14" smd rect
			(at -2.54 -2)
			(size 0.74 2.8)
			(layers "F.Cu" "F.Mask" "F.Paste")
			(net 1276 "/USER_IO.B14")
			(pintype "passive")
		)
		(pad "15" smd rect
			(at -1.27 1.999)
			(size 0.74 2.8)
			(layers "F.Cu" "F.Mask" "F.Paste")
			(net 1277 "/USER_IO.B15")
			(pintype "passive")
		)
		(pad "16" smd rect
			(at -1.27 -2)
			(size 0.74 2.8)
			(layers "F.Cu" "F.Mask" "F.Paste")
			(net 1278 "/USER_IO.B16")
			(pintype "passive")
		)
		(pad "17" smd rect
			(at 0 1.999)
			(size 0.74 2.8)
			(layers "F.Cu" "F.Mask" "F.Paste")
			(net 1279 "/USER_IO.B17")
			(pintype "passive")
		)
		(pad "18" smd rect
			(at 0 -2)
			(size 0.74 2.8)
			(layers "F.Cu" "F.Mask" "F.Paste")
			(net 1280 "/USER_IO.B18")
			(pintype "passive")
		)
		(pad "19" smd rect
			(at 1.269 1.999)
			(size 0.74 2.8)
			(layers "F.Cu" "F.Mask" "F.Paste")
			(net 1281 "/USER_IO.B19")
			(pintype "passive")
		)
		(pad "20" smd rect
			(at 1.269 -2)
			(size 0.74 2.8)
			(layers "F.Cu" "F.Mask" "F.Paste")
			(net 1 "GND")
			(pintype "passive")
		)
		(pad "21" smd rect
			(at 2.539 1.999)
			(size 0.74 2.8)
			(layers "F.Cu" "F.Mask" "F.Paste")
			(net 1282 "/USER_IO.B21")
			(pintype "passive")
		)
		(pad "22" smd rect
			(at 2.539 -2)
			(size 0.74 2.8)
			(layers "F.Cu" "F.Mask" "F.Paste")
			(net 24 "+3V3")
			(pintype "passive")
		)
		(pad "23" smd rect
			(at 3.809 1.999)
			(size 0.74 2.8)
			(layers "F.Cu" "F.Mask" "F.Paste")
			(net 1283 "/USER_IO.B23")
			(pintype "passive")
		)
		(pad "24" smd rect
			(at 3.809 -2)
			(size 0.74 2.8)
			(layers "F.Cu" "F.Mask" "F.Paste")
			(net 1284 "/USER_IO.B24")
			(pintype "passive")
		)
		(pad "25" smd rect
			(at 5.078 1.999)
			(size 0.74 2.8)
			(layers "F.Cu" "F.Mask" "F.Paste")
			(net 1285 "/USER_IO.B25")
			(pintype "passive")
		)
		(pad "26" smd rect
			(at 5.078 -2)
			(size 0.74 2.8)
			(layers "F.Cu" "F.Mask" "F.Paste")
			(net 1286 "/USER_IO.B26")
			(pintype "passive")
		)
		(pad "27" smd rect
			(at 6.349 1.999)
			(size 0.74 2.8)
			(layers "F.Cu" "F.Mask" "F.Paste")
			(net 1287 "/USER_IO.B27")
			(pintype "passive")
		)
		(pad "28" smd rect
			(at 6.349 -2)
			(size 0.74 2.8)
			(layers "F.Cu" "F.Mask" "F.Paste")
			(net 1288 "/USER_IO.B28")
			(pintype "passive")
		)
		(pad "29" smd rect
			(at 7.618 1.999)
			(size 0.74 2.8)
			(layers "F.Cu" "F.Mask" "F.Paste")
			(net 1289 "/USER_IO.B29")
			(pintype "passive")
		)
		(pad "30" smd rect
			(at 7.618 -2)
			(size 0.74 2.8)
			(layers "F.Cu" "F.Mask" "F.Paste")
			(net 1290 "/USER_IO.B30")
			(pintype "passive")
		)
		(pad "31" smd rect
			(at 8.89 1.999)
			(size 0.74 2.8)
			(layers "F.Cu" "F.Mask" "F.Paste")
			(net 1291 "/USER_IO.B31")
			(pintype "passive")
		)
		(pad "32" smd rect
			(at 8.89 -2)
			(size 0.74 2.8)
			(layers "F.Cu" "F.Mask" "F.Paste")
			(net 1292 "/USER_IO.B32")
			(pintype "passive")
		)
		(pad "33" smd rect
			(at 10.159 1.999)
			(size 0.74 2.8)
			(layers "F.Cu" "F.Mask" "F.Paste")
			(net 1293 "/USER_IO.B33")
			(pintype "passive")
		)
		(pad "34" smd rect
			(at 10.159 -2)
			(size 0.74 2.8)
			(layers "F.Cu" "F.Mask" "F.Paste")
			(net 1 "GND")
			(pintype "passive")
		)
	)
	(footprint "antmicro-footprints:C_0402_1005Metric"
		(layer "F.Cu")
		(at 173.570001 113.143751 180)
		(descr "Capacitor SMD 0402")
		(tags "capacitor SMD 0402")
		(property "Reference" "C302"
			(at -3.729999 -0.356249 0)
			(layer "F.SilkS")
			(effects
				(font
					(size 0.7 0.7)
					(thickness 0.15)
				)
				(justify right bottom)
			)
		)
		(property "Value" "C_100n_0402"
			(at 0 1.4 0)
			(layer "F.Fab")
			(effects
				(font
					(size 0.7 0.7)
					(thickness 0.15)
				)
				(justify right bottom)
			)
		)
		(property "Description" "SMD Multilayer Ceramic Capacitor, 0.1 µF, 50 V, 0402 [1005 Metric], ± 10%, X5R, GRM Series"
			(at 0 0 180)
			(layer "F.Fab")
			(hide yes)
			(effects
				(font
					(size 1.27 1.27)
					(thickness 0.15)
				)
			)
		)
		(property "Author" "Antmicro"
			(at 347.140002 226.287502 0)
			(layer "F.Fab")
			(hide yes)
			(effects
				(font
					(size 1 1)
					(thickness 0.15)
				)
			)
		)
		(property "Dielectric" "X5R"
			(at 347.140002 226.287502 0)
			(layer "F.Fab")
			(hide yes)
			(effects
				(font
					(size 1 1)
					(thickness 0.15)
				)
			)
		)
		(property "License" "Apache-2.0"
			(at 347.140002 226.287502 0)
			(layer "F.Fab")
			(hide yes)
			(effects
				(font
					(size 1 1)
					(thickness 0.15)
				)
			)
		)
		(property "MPN" "GRM155R61H104KE14D"
			(at 347.140002 226.287502 0)
			(layer "F.Fab")
			(hide yes)
			(effects
				(font
					(size 1 1)
					(thickness 0.15)
				)
			)
		)
		(property "Manufacturer" "Murata"
			(at 347.140002 226.287502 0)
			(layer "F.Fab")
			(hide yes)
			(effects
				(font
					(size 1 1)
					(thickness 0.15)
				)
			)
		)
		(property "Val" "100n"
			(at 347.140002 226.287502 0)
			(layer "F.Fab")
			(hide yes)
			(effects
				(font
					(size 1 1)
					(thickness 0.15)
				)
			)
		)
		(property "Voltage" "50V"
			(at 347.140002 226.287502 0)
			(layer "F.Fab")
			(hide yes)
			(effects
				(font
					(size 1 1)
					(thickness 0.15)
				)
			)
		)
		(sheetname "FMC+ HSPC")
		(sheetfile "fmc-hspc.kicad_sch")
		(attr smd)
		(fp_rect
			(start -0.925 -0.47)
			(end 0.925 0.47)
			(stroke
				(width 0.05)
				(type default)
			)
			(fill no)
			(layer "F.CrtYd")
		)
		(fp_line
			(start 0.504 0.248)
			(end -0.494 0.248)
			(stroke
				(width 0.15)
				(type solid)
			)
			(layer "F.Fab")
		)
		(fp_line
			(start 0.504 -0.25)
			(end 0.504 0.248)
			(stroke
				(width 0.15)
				(type solid)
			)
			(layer "F.Fab")
		)
		(fp_line
			(start -0.494 0.248)
			(end -0.494 -0.25)
			(stroke
				(width 0.15)
				(type solid)
			)
			(layer "F.Fab")
		)
		(fp_line
			(start -0.494 -0.25)
			(end 0.504 -0.25)
			(stroke
				(width 0.15)
				(type solid)
			)
			(layer "F.Fab")
		)
		(pad "1" smd roundrect
			(at -0.48 0 180)
			(size 0.59 0.64)
			(layers "F.Cu" "F.Mask" "F.Paste")
			(roundrect_rratio 0.25)
			(net 73 "/FMC+ HSPC/GTX116.TX1_P")
			(pintype "passive")
		)
		(pad "2" smd roundrect
			(at 0.48 0 180)
			(size 0.59 0.64)
			(layers "F.Cu" "F.Mask" "F.Paste")
			(roundrect_rratio 0.25)
			(net 71 "/FMC+ HSPC/GTX_TX2_C_P")
			(pintype "passive")
		)
	)
	(footprint "antmicro-footprints:C_1206_3216Metric"
		(layer "F.Cu")
		(at 195.8 184.449 90)
		(descr "Capacitor SMD 1206")
		(tags "capacitor SMD 1206")
		(property "Reference" "C200"
			(at -1.501 -1.15 90)
			(layer "F.SilkS")
			(effects
				(font
					(size 0.7 0.7)
					(thickness 0.15)
				)
				(justify left bottom)
			)
		)
		(property "Value" "C_47u_16V_1206"
			(at 0 2.1 90)
			(layer "F.Fab")
			(effects
				(font
					(size 0.7 0.7)
					(thickness 0.15)
				)
				(justify left bottom)
			)
		)
		(property "Description" "SMD Multilayer Ceramic Capacitor, 47 µF, 16 V, 1206 [3216 Metric], ± 20%, X5R, C"
			(at 0 0 90)
			(layer "F.Fab")
			(hide yes)
			(effects
				(font
					(size 1.27 1.27)
					(thickness 0.15)
				)
			)
		)
		(property "Author" "Antmicro"
			(at 380.249 -11.351 0)
			(layer "F.Fab")
			(hide yes)
			(effects
				(font
					(size 1 1)
					(thickness 0.15)
				)
			)
		)
		(property "Dielectric" "X5R"
			(at 380.249 -11.351 0)
			(layer "F.Fab")
			(hide yes)
			(effects
				(font
					(size 1 1)
					(thickness 0.15)
				)
			)
		)
		(property "License" "Apache-2.0"
			(at 380.249 -11.351 0)
			(layer "F.Fab")
			(hide yes)
			(effects
				(font
					(size 1 1)
					(thickness 0.15)
				)
			)
		)
		(property "MPN" "C3216X5R1C476M160AB"
			(at 380.249 -11.351 0)
			(layer "F.Fab")
			(hide yes)
			(effects
				(font
					(size 1 1)
					(thickness 0.15)
				)
			)
		)
		(property "Manufacturer" "TDK"
			(at 380.249 -11.351 0)
			(layer "F.Fab")
			(hide yes)
			(effects
				(font
					(size 1 1)
					(thickness 0.15)
				)
			)
		)
		(property "Val" "47u"
			(at 380.249 -11.351 0)
			(layer "F.Fab")
			(hide yes)
			(effects
				(font
					(size 1 1)
					(thickness 0.15)
				)
			)
		)
		(property "Voltage" "16V"
			(at 380.249 -11.351 0)
			(layer "F.Fab")
			(hide yes)
			(effects
				(font
					(size 1 1)
					(thickness 0.15)
				)
			)
		)
		(sheetname "Power supply")
		(sheetfile "power-supply.kicad_sch")
		(attr smd)
		(fp_line
			(start 0.8 -0.899)
			(end -0.8 -0.899)
			(stroke
				(width 0.15)
				(type solid)
			)
			(layer "F.SilkS")
		)
		(fp_line
			(start 0.8 0.901)
			(end -0.8 0.901)
			(stroke
				(width 0.15)
				(type solid)
			)
			(layer "F.SilkS")
		)
		(fp_rect
			(start -2.325 -1.15)
			(end 2.325 1.15)
			(stroke
				(width 0.05)
				(type default)
			)
			(fill no)
			(layer "F.CrtYd")
		)
		(fp_rect
			(start -1.6 -0.799)
			(end 1.6 0.801)
			(stroke
				(width 0.15)
				(type solid)
			)
			(fill no)
			(layer "F.Fab")
		)
		(pad "1" smd roundrect
			(at -1.5 0.001 90)
			(size 1.15 1.8)
			(layers "F.Cu" "F.Mask" "F.Paste")
			(roundrect_rratio 0.25)
			(net 1 "GND")
			(pintype "passive")
		)
		(pad "2" smd roundrect
			(at 1.5 0.001 90)
			(size 1.15 1.8)
			(layers "F.Cu" "F.Mask" "F.Paste")
			(roundrect_rratio 0.25)
			(net 956 "/DC-DC Converters/POE_DC")
			(pintype "passive")
		)
	)
)
